(kicad_pcb
	(version 20221018)
	(generator pcbnew)
	(general
    (thickness 1.62)
  )
	(paper "A4")
	(title_block
    (title "ECP5 - Datacenter Secure Control Module (DC-SCM)")
    (date "2024-07-01")
    (rev "1.2.1")
		(comment 9 "footprints 184-189 of 506")
	)
	(layers
    (0 "F.Cu" signal)
    (1 "In1.Cu" power)
    (2 "In2.Cu" signal)
    (3 "In3.Cu" power)
    (4 "In4.Cu" power)
    (5 "In5.Cu" signal)
    (6 "In6.Cu" power)
    (31 "B.Cu" signal)
    (32 "B.Adhes" user "B.Adhesive")
    (33 "F.Adhes" user "F.Adhesive")
    (34 "B.Paste" user)
    (35 "F.Paste" user)
    (36 "B.SilkS" user "B.Silkscreen")
    (37 "F.SilkS" user "F.Silkscreen")
    (38 "B.Mask" user)
    (39 "F.Mask" user)
    (40 "Dwgs.User" user "User.Drawings")
    (41 "Cmts.User" user "User.Comments")
    (42 "Eco1.User" user "User.Eco1")
    (43 "Eco2.User" user "User.Eco2")
    (44 "Edge.Cuts" user)
    (45 "Margin" user)
    (46 "B.CrtYd" user "B.Courtyard")
    (47 "F.CrtYd" user "F.Courtyard")
    (48 "B.Fab" user)
    (49 "F.Fab" user)
  )
	(footprint "antmicro-footprints:USB-Micro-B_Receptacle_Amphenol_10118192" (layer "F.Cu")
    (at 126.24 62.069 180)
    (property "Author" "Antmicro")
    (property "License" "Apache-2.0")
    (property "MPN" "10118192-0001LF")
    (property "Manufacturer" "Amphenol")
    (property "Sheetfile" "interfaces.kicad_sch")
    (property "Sheetname" "Interfaces")
    (property "ki_description" "USB - micro B USB 2.0 Receptacle Connector 5 Position Surface Mount, Right Angle")
    (property "ki_keywords" "USB, MICRO, CONNECTOR, SMT, HORIZONTAL")
    (attr smd)
    (fp_text reference "J6" (at 5.925 -3.175) (layer "F.SilkS")
        (effects (font (size 0.7 0.7) (thickness 0.127)))
    )
    (fp_text value "USB-Micro-B_Amphenol_10118192-0001LF" (at 0 4.25) (layer "F.Fab")
        (effects (font (size 1 1) (thickness 0.15)))
    )
    (fp_text user "${REFERENCE}" (at 0 0) (layer "F.Fab")
        (effects (font (size 1 1) (thickness 0.15)))
    )
    (fp_text user "Author: Antmicro" (at -5 7.9 180) (layer "F.Fab") hide
        (effects (font (size 0.7 0.7) (thickness 0.15)) (justify left bottom))
    )
    (fp_text user "License: Apache-2.0" (at -5 9.099 180) (layer "F.Fab") hide
        (effects (font (size 0.7 0.7) (thickness 0.15)) (justify left bottom))
    )
    (fp_line (start -4.05 -1.151) (end -4.05 -0.701)
      (stroke (width 0.15) (type solid)) (layer "F.SilkS"))
    (fp_line (start -1.901 -2.902) (end -1.601 -2.902)
      (stroke (width 0.15) (type solid)) (layer "F.SilkS"))
    (fp_line (start 1.65 -2.902) (end 1.949 -2.902)
      (stroke (width 0.15) (type solid)) (layer "F.SilkS"))
    (fp_line (start 4.049 -1.151) (end 4.049 -0.652)
      (stroke (width 0.15) (type solid)) (layer "F.SilkS"))
    (fp_circle (center -1.75 -3.15) (end -1.7 -3.15)
      (stroke (width 0.15) (type solid)) (fill none) (layer "F.SilkS"))
    (fp_rect (start -4.758 -3.051) (end 4.755 3.048)
      (stroke (width 0.05) (type solid)) (fill none) (layer "F.CrtYd"))
    (fp_line (start -3.951 -2.351) (end -3.951 2.749)
      (stroke (width 0.15) (type solid)) (layer "F.Fab"))
    (fp_line (start -3.951 -2.351) (end -3.5 -2.801)
      (stroke (width 0.15) (type solid)) (layer "F.Fab"))
    (fp_line (start -3.951 2.769) (end 3.95 2.769)
      (stroke (width 0.15) (type solid)) (layer "F.Fab"))
    (fp_line (start 3.95 -2.801) (end -3.5 -2.801)
      (stroke (width 0.15) (type solid)) (layer "F.Fab"))
    (fp_line (start 3.95 2.769) (end 3.95 -2.801)
      (stroke (width 0.15) (type solid)) (layer "F.Fab"))
    (pad "1" smd rect (at -1.301 -2.226 180) (size 0.4 1.35) (layers "F.Cu" "F.Paste" "F.Mask")
      (net 415 "VBUS") (pinfunction "VBUS") (pintype "passive"))
    (pad "2" smd rect (at -0.651 -2.226 180) (size 0.4 1.35) (layers "F.Cu" "F.Paste" "F.Mask")
      (net 416 "DBG_USB_D_N") (pinfunction "D-") (pintype "bidirectional"))
    (pad "3" smd rect (at 0 -2.226 180) (size 0.4 1.35) (layers "F.Cu" "F.Paste" "F.Mask")
      (net 417 "DBG_USB_D_P") (pinfunction "D+") (pintype "bidirectional"))
    (pad "4" smd rect (at 0.65 -2.226 180) (size 0.4 1.35) (layers "F.Cu" "F.Paste" "F.Mask")
      (net 388 "Net-(J6-ID)") (pinfunction "ID") (pintype "bidirectional"))
    (pad "5" smd rect (at 1.3 -2.226 180) (size 0.4 1.35) (layers "F.Cu" "F.Paste" "F.Mask")
      (net 1 "GND") (pinfunction "GND") (pintype "power_in"))
    (pad "SH" smd roundrect (at -3.801 0.449 180) (size 1.8 1.9) (layers "F.Cu" "F.Paste" "F.Mask") (roundrect_rratio 0.1)
      (net 1 "GND") (pinfunction "SHIELD") (pintype "passive"))
    (pad "SH" smd roundrect (at -3.101 -2.101 180) (size 2.1 1.6) (layers "F.Cu" "F.Paste" "F.Mask") (roundrect_rratio 0.1)
      (net 1 "GND") (pinfunction "SHIELD") (pintype "passive"))
    (pad "SH" smd roundrect (at -1.2 0.449 180) (size 1.9 1.9) (layers "F.Cu" "F.Paste" "F.Mask") (roundrect_rratio 0.1)
      (net 1 "GND") (pinfunction "SHIELD") (pintype "passive"))
    (pad "SH" smd roundrect (at 1.199 0.449 180) (size 1.9 1.9) (layers "F.Cu" "F.Paste" "F.Mask") (roundrect_rratio 0.1)
      (net 1 "GND") (pinfunction "SHIELD") (pintype "passive"))
    (pad "SH" smd roundrect (at 3.1 -2.101 180) (size 2.1 1.6) (layers "F.Cu" "F.Paste" "F.Mask") (roundrect_rratio 0.1)
      (net 1 "GND") (pinfunction "SHIELD") (pintype "passive"))
    (pad "SH" smd roundrect (at 3.8 0.449 180) (size 1.8 1.9) (layers "F.Cu" "F.Paste" "F.Mask") (roundrect_rratio 0.1)
      (net 1 "GND") (pinfunction "SHIELD") (pintype "passive"))
  )
	(footprint "antmicro-footprints:C_0402_1005Metric" (layer "F.Cu")
    (at 78.28 79.07 180)
    (descr "Capacitor SMD 0402")
    (tags "capacitor SMD 0402")
    (property "Author" "Antmicro")
    (property "Dielectric" "")
    (property "License" "Apache-2.0")
    (property "MPN" "CC0402MRX5R5BB106")
    (property "Manufacturer" "YAGEO")
    (property "Public" "False")
    (property "Sheetfile" "power-supply.kicad_sch")
    (property "Sheetname" "Power supply")
    (property "Val" "10u")
    (property "Voltage" "")
    (property "ki_description" "SMD Multilayer Ceramic Capacitor, 10 µF, 6.3 V, 0402 [1005 Metric], ± 20%, X5R, CC Series")
    (property "ki_keywords" "0402, SMT, CAPACITOR, PASSIVE, MLCC, CERAMIC")
    (attr smd)
    (fp_text reference "C262" (at -2.43 -0.015) (layer "F.SilkS")
        (effects (font (size 0.7 0.7) (thickness 0.127)))
    )
    (fp_text value "C_10u_0402" (at 0 1.17) (layer "F.Fab")
        (effects (font (size 1 1) (thickness 0.15)))
    )
    (fp_text user "Author: Antmicro" (at -0.939 3.399 180) (layer "F.Fab") hide
        (effects (font (size 0.7 0.7) (thickness 0.15)) (justify left bottom))
    )
    (fp_text user "License: Apache-2.0" (at -0.939 5.799 180) (layer "F.Fab") hide
        (effects (font (size 0.7 0.7) (thickness 0.15)) (justify left bottom))
    )
    (fp_text user "${REFERENCE}" (at 0 0) (layer "F.Fab")
        (effects (font (size 0.25 0.25) (thickness 0.04)))
    )
    (fp_rect (start -0.925 -0.47) (end 0.925 0.47)
      (stroke (width 0.05) (type default)) (fill none) (layer "F.CrtYd"))
    (fp_line (start -0.494 -0.25) (end 0.504 -0.25)
      (stroke (width 0.15) (type solid)) (layer "F.Fab"))
    (fp_line (start -0.494 0.248) (end -0.494 -0.25)
      (stroke (width 0.15) (type solid)) (layer "F.Fab"))
    (fp_line (start 0.504 -0.25) (end 0.504 0.248)
      (stroke (width 0.15) (type solid)) (layer "F.Fab"))
    (fp_line (start 0.504 0.248) (end -0.494 0.248)
      (stroke (width 0.15) (type solid)) (layer "F.Fab"))
    (pad "1" smd roundrect (at -0.48 0 180) (size 0.59 0.64) (layers "F.Cu" "F.Paste" "F.Mask") (roundrect_rratio 0.25)
      (net 1 "GND") (pintype "passive"))
    (pad "2" smd roundrect (at 0.48 0 180) (size 0.59 0.64) (layers "F.Cu" "F.Paste" "F.Mask") (roundrect_rratio 0.25)
      (net 270 "/Power supply/5V0_PG") (pintype "passive"))
  )
	(footprint "antmicro-footprints:R_0402_1005Metric" (layer "F.Cu")
    (at 80.24 73.64 -90)
    (descr "Resistor SMD 0402")
    (tags "resistor SMD 0402")
    (property "Author" "Antmicro")
    (property "License" "Apache-2.0")
    (property "MPN" "CR0402-FX-1003GLF")
    (property "Manufacturer" "Bourns")
    (property "Public" "False")
    (property "Sheetfile" "power-supply.kicad_sch")
    (property "Sheetname" "Power supply")
    (property "Tolerance" "1%")
    (property "Val" "100k")
    (property "ki_description" "SMD Chip Resistor, 100 kohm, ± 1%, 62.5 mW, 0402 [1005 Metric], Thick Film, General Purpose")
    (property "ki_keywords" "0402, SMT, RESISTOR, PASSIVE")
    (attr smd)
    (fp_text reference "R8" (at -2.128167 4.86 90) (layer "F.SilkS")
        (effects (font (size 0.7 0.7) (thickness 0.127)))
    )
    (fp_text value "R_100k_0402" (at 0 1.17 90) (layer "F.Fab")
        (effects (font (size 1 1) (thickness 0.15)))
    )
    (fp_text user "License: Apache-2.0" (at -0.95 5.169 -90) (layer "F.Fab") hide
        (effects (font (size 0.7 0.7) (thickness 0.15)) (justify left bottom))
    )
    (fp_text user "${REFERENCE}" (at 0 0 90) (layer "F.Fab")
        (effects (font (size 0.25 0.25) (thickness 0.04)))
    )
    (fp_text user "Author: Antmicro" (at -0.95 4.169 -90) (layer "F.Fab") hide
        (effects (font (size 0.7 0.7) (thickness 0.15)) (justify left bottom))
    )
    (fp_rect (start -0.925 -0.47) (end 0.925 0.47)
      (stroke (width 0.05) (type default)) (fill none) (layer "F.CrtYd"))
    (fp_rect (start -0.5 -0.25) (end 0.5 0.25)
      (stroke (width 0.15) (type solid)) (fill none) (layer "F.Fab"))
    (pad "1" smd roundrect (at -0.48 0 270) (size 0.59 0.64) (layers "F.Cu" "F.Paste" "F.Mask") (roundrect_rratio 0.25)
      (net 11 "VCC5V0") (pintype "passive"))
    (pad "2" smd roundrect (at 0.48 0 270) (size 0.59 0.64) (layers "F.Cu" "F.Paste" "F.Mask") (roundrect_rratio 0.25)
      (net 270 "/Power supply/5V0_PG") (pintype "passive"))
  )
	(footprint "antmicro-footprints:TP_SMD_1mm" (layer "F.Cu")
    (at 83.025 106.225)
    (property "Author" "Antmicro")
    (property "License" "Apache-2.0")
    (property "MPN" "")
    (property "Manufacturer" "")
    (property "Sheetfile" "interfaces.kicad_sch")
    (property "Sheetname" "Interfaces")
    (property "exclude_from_bom" "")
    (property "ki_description" "Test point 1mm SMD")
    (property "ki_keywords" "TESTPOINT")
    (attr exclude_from_pos_files exclude_from_bom)
    (fp_text reference "TP16" (at -1.315 1.66) (layer "F.SilkS")
        (effects (font (size 0.7 0.7) (thickness 0.15)) (justify left bottom))
    )
    (fp_text value "TP_1mm_SMD" (at 0 1.4) (layer "F.Fab")
        (effects (font (size 0.7 0.7) (thickness 0.15)) (justify left bottom))
    )
    (fp_text user "License: Apache-2.0" (at -0.5 5.2) (layer "F.Fab") hide
        (effects (font (size 0.7 0.7) (thickness 0.15)) (justify left bottom))
    )
    (fp_text user "${REFERENCE}" (at -0.5 2.8) (layer "F.Fab") hide
        (effects (font (size 0.7 0.7) (thickness 0.15)) (justify left bottom))
    )
    (fp_text user "Author: Antmicro" (at -0.5 4) (layer "F.Fab") hide
        (effects (font (size 0.7 0.7) (thickness 0.15)) (justify left bottom))
    )
    (fp_circle (center 0 0) (end 0.6 0)
      (stroke (width 0.05) (type default)) (fill none) (layer "F.CrtYd"))
    (pad "1" smd circle (at 0 0) (size 1 1) (layers "F.Cu" "F.Mask")
      (net 437 "Net-(U6-DS)") (pinfunction "1") (pintype "passive"))
  )
	(footprint "antmicro-footprints:R_0603_1608Metric" (layer "F.Cu")
    (at 74.55 87.2 90)
    (descr "Resistor SMD 0603")
    (tags "resistor SMD 0603")
    (property "Author" "Antmicro")
    (property "Current" "1A")
    (property "License" "Apache-2.0")
    (property "MPN" "CR0603-J/-000ELF")
    (property "Manufacturer" "Bourns")
    (property "Public" "False")
    (property "Sheetfile" "power-supply.kicad_sch")
    (property "Sheetname" "Power supply")
    (property "Tolerance" "")
    (property "Val" "0R")
    (property "ki_description" "Zero Ohm Resistor, Jumper, 0603 [1608 Metric], Thick Film, 100 mW, 1 A, Surface Mount Device, CR")
    (property "ki_keywords" "0603, SMT, RESISTOR, PASSIVE")
    (attr smd)
    (fp_text reference "R144" (at 0.175 -0.97 90) (layer "F.SilkS")
        (effects (font (size 0.7 0.7) (thickness 0.127)))
    )
    (fp_text value "R_0R_0603" (at 0 1.9 90) (layer "F.Fab")
        (effects (font (size 1 1) (thickness 0.15)))
    )
    (fp_text user "${REFERENCE}" (at -1.25 3.898 90) (layer "F.Fab") hide
        (effects (font (size 0.7 0.7) (thickness 0.15)) (justify left bottom))
    )
    (fp_text user "Author: Antmicro" (at -1.25 4.9 90) (layer "F.Fab") hide
        (effects (font (size 0.7 0.7) (thickness 0.15)) (justify left bottom))
    )
    (fp_text user "License: Apache-2.0" (at -1.25 5.9 90) (layer "F.Fab") hide
        (effects (font (size 0.7 0.7) (thickness 0.15)) (justify left bottom))
    )
    (fp_line (start -0.15 -0.4) (end 0.15 -0.4)
      (stroke (width 0.15) (type solid)) (layer "F.SilkS"))
    (fp_line (start -0.15 0.4) (end 0.15 0.4)
      (stroke (width 0.15) (type solid)) (layer "F.SilkS"))
    (fp_rect (start -1.25 -0.65) (end 1.25 0.65)
      (stroke (width 0.05) (type solid)) (fill none) (layer "F.CrtYd"))
    (fp_rect (start -0.8 -0.4) (end 0.8 0.4)
      (stroke (width 0.15) (type solid)) (fill none) (layer "F.Fab"))
    (pad "1" smd roundrect (at -0.7 0 90) (size 0.8 1) (layers "F.Cu" "F.Paste" "F.Mask") (roundrect_rratio 0.2)
      (net 12 "VCC1V0") (pintype "passive"))
    (pad "2" smd roundrect (at 0.7 0 90) (size 0.8 1) (layers "F.Cu" "F.Paste" "F.Mask") (roundrect_rratio 0.2)
      (net 358 "Net-(C121-Pad2)") (pintype "passive"))
  )
	(footprint "antmicro-footprints:QFN-8_2x1.5mm" (layer "F.Cu")
    (at 89.1 86.15 90)
    (property "Author" "Antmicro")
    (property "License" "Apache-2.0")
    (property "MPN" "TPS62823DLCT")
    (property "Manufacturer" "Texas Instruments")
    (property "Sheetfile" "power-supply.kicad_sch")
    (property "Sheetname" "Power supply")
    (property "ki_description" "DC/DC converter")
    (property "ki_keywords" "SMT, PMIC, IC, SWITCHING, VOLTAGE, REGULATOR, DC-DC")
    (attr smd)
    (fp_text reference "U16" (at -0.455 1.96 90) (layer "F.SilkS")
        (effects (font (size 0.7 0.7) (thickness 0.127)))
    )
    (fp_text value "TPS62823DLCT" (at 0 2.075 90) (layer "F.Fab")
        (effects (font (size 1 1) (thickness 0.15)))
    )
    (fp_text user "Author: Antmicro" (at -1.651 5.275 90) (layer "F.Fab") hide
        (effects (font (size 0.7 0.7) (thickness 0.15)) (justify left bottom))
    )
    (fp_text user "${REFERENCE}" (at 0 0 90) (layer "F.Fab")
        (effects (font (size 0.5 0.5) (thickness 0.075)))
    )
    (fp_text user "License: Apache-2.0" (at -1.651 6.475 90) (layer "F.Fab") hide
        (effects (font (size 0.7 0.7) (thickness 0.15)) (justify left bottom))
    )
    (fp_line (start -0.9 1.05) (end 0.9 1.05)
      (stroke (width 0.15) (type solid)) (layer "F.SilkS"))
    (fp_line (start -0.25 -1.05) (end 0.9 -1.05)
      (stroke (width 0.15) (type solid)) (layer "F.SilkS"))
    (fp_circle (center -0.9 -1.05) (end -0.849 -1.05)
      (stroke (width 0.15) (type solid)) (fill solid) (layer "F.SilkS"))
    (fp_rect (start -1.1 -1.25) (end 1.1 1.25)
      (stroke (width 0.05) (type solid)) (fill none) (layer "F.CrtYd"))
    (fp_line (start -1 -0.5) (end -0.5 -1)
      (stroke (width 0.15) (type solid)) (layer "F.Fab"))
    (fp_line (start -1 0.998) (end -1 -0.5)
      (stroke (width 0.15) (type solid)) (layer "F.Fab"))
    (fp_line (start -0.5 -1) (end 0.998 -1)
      (stroke (width 0.15) (type solid)) (layer "F.Fab"))
    (fp_line (start 0.998 -1) (end 0.998 0.998)
      (stroke (width 0.15) (type solid)) (layer "F.Fab"))
    (fp_line (start 0.998 0.998) (end -1 0.998)
      (stroke (width 0.15) (type solid)) (layer "F.Fab"))
    (pad "1" smd rect (at -0.677 -0.75 90) (size 0.55 0.25) (layers "F.Cu" "F.Paste" "F.Mask")
      (net 230 "/Power supply/VCCAUX_EN") (pinfunction "EN") (pintype "input"))
    (pad "2" smd rect (at -0.677 -0.25 90) (size 0.55 0.25) (layers "F.Cu" "F.Paste" "F.Mask")
      (net 301 "Net-(U16-FB)") (pinfunction "FB") (pintype "bidirectional"))
    (pad "3" smd rect (at -0.677 0.248 90) (size 0.55 0.25) (layers "F.Cu" "F.Paste" "F.Mask")
      (net 1 "GND") (pinfunction "AGND") (pintype "power_in"))
    (pad "4" smd rect (at -0.677 0.748 90) (size 0.55 0.25) (layers "F.Cu" "F.Paste" "F.Mask")
      (net 542 "unconnected-(U16-NC-Pad4)") (pinfunction "NC") (pintype "no_connect"))
    (pad "5" smd rect (at 0.675 0.748 90) (size 0.55 0.25) (layers "F.Cu" "F.Paste" "F.Mask")
      (net 1 "GND") (pinfunction "PGND") (pintype "power_in"))
    (pad "6" smd rect (at 0.675 0.248 90) (size 0.55 0.25) (layers "F.Cu" "F.Paste" "F.Mask")
      (net 393 "Net-(U16-SW)") (pinfunction "SW") (pintype "bidirectional"))
    (pad "7" smd rect (at 0.675 -0.25 90) (size 0.55 0.25) (layers "F.Cu" "F.Paste" "F.Mask")
      (net 11 "VCC5V0") (pinfunction "VIN") (pintype "power_in"))
    (pad "8" smd rect (at 0.675 -0.75 90) (size 0.55 0.25) (layers "F.Cu" "F.Paste" "F.Mask")
      (net 236 "/Power supply/2V5_PG") (pinfunction "PG") (pintype "output"))
  )
)
